FILE_TYPE = CONNECTIVITY;
{Allegro Design Entry HDL 17.4-2019 S026 (4007227) 1/17/2022}
"PAGE_NUMBER" = 78;
0"NC";
END.
